# S9S_MB_2U (Grand Teton) — schematic netlist excerpt (pin names and nets, part order shuffled) for the footprints in the layout excerpt that follows; sources: Cadence DE-HDL packaged netlist, KiCad conversion of 03242023_DA0F0TMBIJ0_F0T_Motherboard_J_brd_V01_OCP.brd

U51  PCA9555APW  IC  pkg TSSOP24XB  page 164
  \int#\  = FM_SMB_CPU1_ALERT
  A1  = PD_SMB_OCP2_HP_ADD1
  A2  = PD_SMB_OCP2_HP_ADD2
  P0_0  = TP_PCA9555_U51_P00
  P0_1  = TP_PCA9555_U51_P01
  P0_2  = HP_OCP_V3_2_EN
  P0_3  = HP_LVC3_OCP_V3_2_ATTN_OUT_SW_N
  P0_4  = HP_LVC3_OCP_V3_2_PRSNT2_N
  P0_5  = TP_PCA9555_U51_P05
  P0_6  = TP_PCA9555_U51_P06
  P0_7  = TP_PCA9555_U51_P07
  VSS  = GND
  P1_0  = TP_PCA9555_U51_P10
  P1_1  = TP_PCA9555_U51_P11
  P1_2  = TP_PCA9555_U51_P12
  P1_3  = TP_PCA9555_U51_P13
  P1_4  = TP_PCA9555_U51_P14
  P1_5  = TP_PCA9555_U51_P15
  P1_6  = TP_PCA9555_U51_P16
  P1_7  = TP_PCA9555_U51_P17
  A0  = PD_SMB_OCP2_HP_ADD0
  SCL  = SMB_PEHPCPU1_LVC3_R3_SCL
  SDA  = SMB_PEHPCPU1_LVC3_R3_SDA
  VDD  = P3V3_AUX

(kicad_pcb
	(version 20260206)
	(generator "pcbnew")
	(generator_version "10.0")
	(general
		(thickness 1.6)
		(legacy_teardrops no)
	)
	(paper "A4")
	(title_block
		(title "03242023_DA0F0TMBIJ0_F0T_Motherboard_J_brd_V01_OCP.brd")
		(comment 1 "Grand Teton / footprints 1914-1914 of 6105")
	)
	(layers
		(0 "F.Cu" signal "TOP")
		(4 "In1.Cu" signal "GND")
		(6 "In2.Cu" signal "IN1")
		(8 "In3.Cu" signal "GND1")
		(10 "In4.Cu" signal "IN2")
		(12 "In5.Cu" signal "GND2")
		(14 "In6.Cu" signal "IN3")
		(16 "In7.Cu" signal "GND3")
		(18 "In8.Cu" signal "VCC")
		(20 "In9.Cu" signal "VCC1")
		(22 "In10.Cu" signal "GND4")
		(24 "In11.Cu" signal "IN4")
		(26 "In12.Cu" signal "GND5")
		(28 "In13.Cu" signal "IN5")
		(30 "In14.Cu" signal "GND6")
		(32 "In15.Cu" signal "IN6")
		(34 "In16.Cu" signal "GND7")
		(2 "B.Cu" signal "BOTTOM")
		(9 "F.Adhes" user "F.Adhesive")
		(11 "B.Adhes" user "B.Adhesive")
		(13 "F.Paste" user "Package Geometry/Pastemask Top")
		(15 "B.Paste" user "Package Geometry/Pastemask Bottom")
		(5 "F.SilkS" user "Ref Des/Silkscreen Top")
		(7 "B.SilkS" user "Ref Des/Silkscreen Bottom")
		(1 "F.Mask" user "Board Geometry/Soldermask Top")
		(3 "B.Mask" user "Board Geometry/Soldermask Bottom")
		(17 "Dwgs.User" user "User.Drawings")
		(19 "Cmts.User" user "User.Comments")
		(21 "Eco1.User" user "User.Eco1")
		(23 "Eco2.User" user "User.Eco2")
		(25 "Edge.Cuts" user "Board Geometry/Outline")
		(27 "Margin" user)
		(31 "F.CrtYd" user "Package Geometry/Place Bound Top")
		(29 "B.CrtYd" user "Package Geometry/Place Bound Bottom")
		(35 "F.Fab" user "Ref Des/Assembly Top")
		(33 "B.Fab" user "Ref Des/Assembly Bottom")
	)
	(footprint ""
		(layer "F.Cu")
		(at 140.73378 -121.211848)
		(property "Reference" "U51"
			(at -2.2606 -4.663948 0)
			(unlocked yes)
			(layer "F.SilkS")
			(effects
				(font
					(size 0.7874 0.5842)
					(thickness 0.1524)
				)
				(justify left)
			)
		)
		(property "Value" ""
			(at 0 0 0)
			(layer "F.Fab")
			(effects
				(font
					(size 1.27 1.27)
				)
			)
		)
		(duplicate_pad_numbers_are_jumpers no)
		(fp_line
			(start -2.097532 -3.949954)
			(end -2.097532 3.949954)
			(stroke
				(width 0.1524)
				(type default)
			)
			(layer "F.SilkS")
		)
		(fp_line
			(start -2.097532 3.949954)
			(end 2.097532 3.949954)
			(stroke
				(width 0.1524)
				(type default)
			)
			(layer "F.SilkS")
		)
		(fp_line
			(start -1.409954 -3.949954)
			(end -2.097532 -3.949954)
			(stroke
				(width 0.1524)
				(type default)
			)
			(layer "F.SilkS")
		)
		(fp_line
			(start 0 -2.54)
			(end -1.409954 -3.949954)
			(stroke
				(width 0.1524)
				(type default)
			)
			(layer "F.SilkS")
		)
		(fp_line
			(start 1.409954 -3.949954)
			(end 0 -2.54)
			(stroke
				(width 0.1524)
				(type default)
			)
			(layer "F.SilkS")
		)
		(fp_line
			(start 2.097532 -3.949954)
			(end 1.409954 -3.949954)
			(stroke
				(width 0.1524)
				(type default)
			)
			(layer "F.SilkS")
		)
		(fp_line
			(start 2.097532 3.949954)
			(end 2.097532 -3.949954)
			(stroke
				(width 0.1524)
				(type default)
			)
			(layer "F.SilkS")
		)
		(fp_poly
			(pts
				(xy -4.7498 -4.182872) (xy -4.7498 -3.166872) (xy -3.7338 -3.674872)
			)
			(stroke
				(width 0)
				(type default)
			)
			(fill yes)
			(layer "F.SilkS")
		)
		(fp_line
			(start -2.249932 -3.949954)
			(end -2.249932 3.949954)
			(stroke
				(width 0.1)
				(type default)
			)
			(layer "F.Fab")
		)
		(fp_line
			(start -2.249932 3.949954)
			(end 2.249932 3.949954)
			(stroke
				(width 0.1)
				(type default)
			)
			(layer "F.Fab")
		)
		(fp_line
			(start 2.249932 -3.949954)
			(end -2.249932 -3.949954)
			(stroke
				(width 0.1)
				(type default)
			)
			(layer "F.Fab")
		)
		(fp_line
			(start 2.249932 3.949954)
			(end 2.249932 -3.949954)
			(stroke
				(width 0.1)
				(type default)
			)
			(layer "F.Fab")
		)
		(fp_poly
			(pts
				(xy -4.7498 -4.182872) (xy -4.7498 -3.166872) (xy -3.7338 -3.674872)
			)
			(stroke
				(width 0)
				(type default)
			)
			(fill yes)
			(layer "F.Fab")
		)
		(pad "1" smd rect
			(at -2.925064 -3.674872 270)
			(size 0.6096 1.3716)
			(layers "F.Cu" "F.Mask" "F.Paste")
			(net "FM_SMB_CPU1_ALERT")
		)
		(pad "2" smd rect
			(at -2.925064 -2.925064 270)
			(size 0.4064 1.3716)
			(layers "F.Cu" "F.Mask" "F.Paste")
			(net "PD_SMB_OCP2_HP_ADD1")
		)
		(pad "3" smd rect
			(at -2.925064 -2.275078 270)
			(size 0.4064 1.3716)
			(layers "F.Cu" "F.Mask" "F.Paste")
			(net "PD_SMB_OCP2_HP_ADD2")
		)
		(pad "4" smd rect
			(at -2.925064 -1.625092 270)
			(size 0.4064 1.3716)
			(layers "F.Cu" "F.Mask" "F.Paste")
			(net "TP_PCA9555_U51_P00")
		)
		(pad "5" smd rect
			(at -2.925064 -0.975106 270)
			(size 0.4064 1.3716)
			(layers "F.Cu" "F.Mask" "F.Paste")
			(net "TP_PCA9555_U51_P01")
		)
		(pad "6" smd rect
			(at -2.925064 -0.32512 270)
			(size 0.4064 1.3716)
			(layers "F.Cu" "F.Mask" "F.Paste")
			(net "HP_OCP_V3_2_EN")
		)
		(pad "7" smd rect
			(at -2.925064 0.32512 270)
			(size 0.4064 1.3716)
			(layers "F.Cu" "F.Mask" "F.Paste")
			(net "HP_LVC3_OCP_V3_2_ATTN_OUT_SW_N")
		)
		(pad "8" smd rect
			(at -2.925064 0.975106 270)
			(size 0.4064 1.3716)
			(layers "F.Cu" "F.Mask" "F.Paste")
			(net "HP_LVC3_OCP_V3_2_PRSNT2_N")
		)
		(pad "9" smd rect
			(at -2.925064 1.625092 270)
			(size 0.4064 1.3716)
			(layers "F.Cu" "F.Mask" "F.Paste")
			(net "TP_PCA9555_U51_P05")
		)
		(pad "10" smd rect
			(at -2.925064 2.275078 270)
			(size 0.4064 1.3716)
			(layers "F.Cu" "F.Mask" "F.Paste")
			(net "TP_PCA9555_U51_P06")
		)
		(pad "11" smd rect
			(at -2.925064 2.925064 270)
			(size 0.4064 1.3716)
			(layers "F.Cu" "F.Mask" "F.Paste")
			(net "TP_PCA9555_U51_P07")
		)
		(pad "12" smd rect
			(at -2.925064 3.674872 270)
			(size 0.6096 1.3716)
			(layers "F.Cu" "F.Mask" "F.Paste")
			(net "GND")
		)
		(pad "13" smd rect
			(at 2.925064 3.674872 270)
			(size 0.6096 1.3716)
			(layers "F.Cu" "F.Mask" "F.Paste")
			(net "TP_PCA9555_U51_P10")
		)
		(pad "14" smd rect
			(at 2.925064 2.925064 270)
			(size 0.4064 1.3716)
			(layers "F.Cu" "F.Mask" "F.Paste")
			(net "TP_PCA9555_U51_P11")
		)
		(pad "15" smd rect
			(at 2.925064 2.275078 270)
			(size 0.4064 1.3716)
			(layers "F.Cu" "F.Mask" "F.Paste")
			(net "TP_PCA9555_U51_P12")
		)
		(pad "16" smd rect
			(at 2.925064 1.625092 270)
			(size 0.4064 1.3716)
			(layers "F.Cu" "F.Mask" "F.Paste")
			(net "TP_PCA9555_U51_P13")
		)
		(pad "17" smd rect
			(at 2.925064 0.975106 270)
			(size 0.4064 1.3716)
			(layers "F.Cu" "F.Mask" "F.Paste")
			(net "TP_PCA9555_U51_P14")
		)
		(pad "18" smd rect
			(at 2.925064 0.32512 270)
			(size 0.4064 1.3716)
			(layers "F.Cu" "F.Mask" "F.Paste")
			(net "TP_PCA9555_U51_P15")
		)
		(pad "19" smd rect
			(at 2.925064 -0.32512 270)
			(size 0.4064 1.3716)
			(layers "F.Cu" "F.Mask" "F.Paste")
			(net "TP_PCA9555_U51_P16")
		)
		(pad "20" smd rect
			(at 2.925064 -0.975106 270)
			(size 0.4064 1.3716)
			(layers "F.Cu" "F.Mask" "F.Paste")
			(net "TP_PCA9555_U51_P17")
		)
		(pad "21" smd rect
			(at 2.925064 -1.625092 270)
			(size 0.4064 1.3716)
			(layers "F.Cu" "F.Mask" "F.Paste")
			(net "PD_SMB_OCP2_HP_ADD0")
		)
		(pad "22" smd rect
			(at 2.925064 -2.275078 270)
			(size 0.4064 1.3716)
			(layers "F.Cu" "F.Mask" "F.Paste")
			(net "SMB_PEHPCPU1_LVC3_R3_SCL")
		)
		(pad "23" smd rect
			(at 2.925064 -2.925064 270)
			(size 0.4064 1.3716)
			(layers "F.Cu" "F.Mask" "F.Paste")
			(net "SMB_PEHPCPU1_LVC3_R3_SDA")
		)
		(pad "24" smd rect
			(at 2.925064 -3.674872 270)
			(size 0.6096 1.3716)
			(layers "F.Cu" "F.Mask" "F.Paste")
			(net "P3V3_AUX")
		)
	)
)
